(kicad_pcb
	(version 20260206)
	(generator "pcbnew")
	(generator_version "10.0")
	(general
		(thickness 1.6)
		(legacy_teardrops no)
	)
	(paper "A4")
	(title_block
		(title "12092022_DA0F0TFB6D0_F0T_FAN_BOARD_MP5048_D_brd_v02_OCP.brd")
		(comment 1 "Grand Teton / footprints 375-380 of 924")
	)
	(layers
		(0 "F.Cu" signal "TOP")
		(4 "In1.Cu" signal "GND")
		(6 "In2.Cu" signal "IN1")
		(8 "In3.Cu" signal "IN2")
		(10 "In4.Cu" signal "GND1")
		(2 "B.Cu" signal "BOTTOM")
		(9 "F.Adhes" user "F.Adhesive")
		(11 "B.Adhes" user "B.Adhesive")
		(13 "F.Paste" user "Package Geometry/Pastemask Top")
		(15 "B.Paste" user "Package Geometry/Pastemask Bottom")
		(5 "F.SilkS" user "Ref Des/Silkscreen Top")
		(7 "B.SilkS" user "Ref Des/Silkscreen Bottom")
		(1 "F.Mask" user "Board Geometry/Soldermask Top")
		(3 "B.Mask" user "Board Geometry/Soldermask Bottom")
		(17 "Dwgs.User" user "User.Drawings")
		(19 "Cmts.User" user "User.Comments")
		(21 "Eco1.User" user "User.Eco1")
		(23 "Eco2.User" user "User.Eco2")
		(25 "Edge.Cuts" user "Board Geometry/Outline")
		(27 "Margin" user)
		(31 "F.CrtYd" user "Package Geometry/Place Bound Top")
		(29 "B.CrtYd" user "Package Geometry/Place Bound Bottom")
		(35 "F.Fab" user "Ref Des/Assembly Top")
		(33 "B.Fab" user "Ref Des/Assembly Bottom")
	)
	(footprint ""
		(layer "F.Cu")
		(at 9.906 -166.878 180)
		(property "Reference" "U24"
			(at 2.00533 -1.016 90)
			(unlocked yes)
			(layer "F.SilkS")
			(effects
				(font
					(size 0.7874 0.5842)
					(thickness 0.1524)
				)
				(justify left)
			)
		)
		(property "Value" ""
			(at 0 0 180)
			(layer "F.Fab")
			(effects
				(font
					(size 1.27 1.27)
				)
			)
		)
		(duplicate_pad_numbers_are_jumpers no)
		(fp_line
			(start 1.3462 1.100074)
			(end -1.3462 1.100074)
			(stroke
				(width 0.1524)
				(type default)
			)
			(layer "F.SilkS")
		)
		(fp_line
			(start 1.3462 -1.100074)
			(end 1.3462 1.100074)
			(stroke
				(width 0.1524)
				(type default)
			)
			(layer "F.SilkS")
		)
		(fp_line
			(start 0.670052 -1.100074)
			(end 1.3462 -1.100074)
			(stroke
				(width 0.1524)
				(type default)
			)
			(layer "F.SilkS")
		)
		(fp_line
			(start 0 -0.381)
			(end 0.670052 -1.100074)
			(stroke
				(width 0.1524)
				(type default)
			)
			(layer "F.SilkS")
		)
		(fp_line
			(start -0.670052 -1.100074)
			(end 0 -0.381)
			(stroke
				(width 0.1524)
				(type default)
			)
			(layer "F.SilkS")
		)
		(fp_line
			(start -1.3462 1.100074)
			(end -1.3462 -1.100074)
			(stroke
				(width 0.1524)
				(type default)
			)
			(layer "F.SilkS")
		)
		(fp_line
			(start -1.3462 -1.100074)
			(end -0.670052 -1.100074)
			(stroke
				(width 0.1524)
				(type default)
			)
			(layer "F.SilkS")
		)
		(fp_poly
			(pts
				(xy -1.524 -0.649986) (xy -2.286 -1.030986) (xy -2.286 -0.268986)
			)
			(stroke
				(width 0)
				(type default)
			)
			(fill yes)
			(layer "F.SilkS")
		)
		(fp_line
			(start 1.100074 0.8001)
			(end 0.670052 0.8001)
			(stroke
				(width 0.1)
				(type default)
			)
			(layer "F.Fab")
		)
		(fp_line
			(start 1.100074 -0.8001)
			(end 1.100074 0.8001)
			(stroke
				(width 0.1)
				(type default)
			)
			(layer "F.Fab")
		)
		(fp_line
			(start 0.670052 1.100074)
			(end -0.670052 1.100074)
			(stroke
				(width 0.1)
				(type default)
			)
			(layer "F.Fab")
		)
		(fp_line
			(start 0.670052 0.8001)
			(end 0.670052 1.100074)
			(stroke
				(width 0.1)
				(type default)
			)
			(layer "F.Fab")
		)
		(fp_line
			(start 0.670052 -0.8001)
			(end 1.100074 -0.8001)
			(stroke
				(width 0.1)
				(type default)
			)
			(layer "F.Fab")
		)
		(fp_line
			(start 0.670052 -0.8001)
			(end 0.670052 0.8001)
			(stroke
				(width 0.1)
				(type default)
			)
			(layer "F.Fab")
		)
		(fp_line
			(start 0.670052 -1.100074)
			(end 0.670052 -0.8001)
			(stroke
				(width 0.1)
				(type default)
			)
			(layer "F.Fab")
		)
		(fp_line
			(start -0.670052 1.100074)
			(end -0.670052 0.8001)
			(stroke
				(width 0.1)
				(type default)
			)
			(layer "F.Fab")
		)
		(fp_line
			(start -0.670052 0.8001)
			(end -0.670052 -0.8001)
			(stroke
				(width 0.1)
				(type default)
			)
			(layer "F.Fab")
		)
		(fp_line
			(start -0.670052 0.8001)
			(end -1.100074 0.8001)
			(stroke
				(width 0.1)
				(type default)
			)
			(layer "F.Fab")
		)
		(fp_line
			(start -0.670052 -0.8001)
			(end -0.670052 -1.100074)
			(stroke
				(width 0.1)
				(type default)
			)
			(layer "F.Fab")
		)
		(fp_line
			(start -0.670052 -1.100074)
			(end 0.670052 -1.100074)
			(stroke
				(width 0.1)
				(type default)
			)
			(layer "F.Fab")
		)
		(fp_line
			(start -1.100074 0.8001)
			(end -1.100074 -0.8001)
			(stroke
				(width 0.1)
				(type default)
			)
			(layer "F.Fab")
		)
		(fp_line
			(start -1.100074 -0.8001)
			(end -0.670052 -0.8001)
			(stroke
				(width 0.1)
				(type default)
			)
			(layer "F.Fab")
		)
		(fp_poly
			(pts
				(xy -1.524 -0.649986) (xy -2.286 -1.030986) (xy -2.286 -0.268986)
			)
			(stroke
				(width 0)
				(type default)
			)
			(fill yes)
			(layer "F.Fab")
		)
		(pad "1" smd rect
			(at -0.94996 -0.649986 90)
			(size 0.4064 0.508)
			(layers "F.Cu" "F.Mask" "F.Paste")
			(net "FAN_2_PRESENT_N")
		)
		(pad "2" smd rect
			(at -0.94996 0 90)
			(size 0.4064 0.508)
			(layers "F.Cu" "F.Mask" "F.Paste")
			(net "GND")
		)
		(pad "3" smd rect
			(at -0.94996 0.649986 90)
			(size 0.4064 0.508)
			(layers "F.Cu" "F.Mask" "F.Paste")
			(net "FAN_3_PRESENT_N")
		)
		(pad "4" smd rect
			(at 0.94996 0.649986 90)
			(size 0.4064 0.508)
			(layers "F.Cu" "F.Mask" "F.Paste")
			(net "FAN_3_PRSNT_BUF_R_N")
		)
		(pad "5" smd rect
			(at 0.94996 0 90)
			(size 0.4064 0.508)
			(layers "F.Cu" "F.Mask" "F.Paste")
			(net "P3V3_AUX")
		)
		(pad "6" smd rect
			(at 0.94996 -0.649986 90)
			(size 0.4064 0.508)
			(layers "F.Cu" "F.Mask" "F.Paste")
			(net "FAN_2_PRSNT_BUF_R_N")
		)
	)
	(footprint ""
		(layer "F.Cu")
		(at 28.829 -124.206 -90)
		(property "Reference" "R4939"
			(at 0 0 270)
			(layer "F.SilkS")
			(hide yes)
			(effects
				(font
					(size 1.27 1.27)
				)
			)
		)
		(property "Value" ""
			(at 0 0 270)
			(layer "F.Fab")
			(effects
				(font
					(size 1.27 1.27)
				)
			)
		)
		(duplicate_pad_numbers_are_jumpers no)
		(fp_line
			(start -0.7874 0.4064)
			(end -0.7874 -0.4064)
			(stroke
				(width 0.1524)
				(type default)
			)
			(layer "F.SilkS")
		)
		(fp_line
			(start 0.7874 0.4064)
			(end -0.7874 0.4064)
			(stroke
				(width 0.1524)
				(type default)
			)
			(layer "F.SilkS")
		)
		(fp_line
			(start -0.7874 -0.4064)
			(end 0.7874 -0.4064)
			(stroke
				(width 0.1524)
				(type default)
			)
			(layer "F.SilkS")
		)
		(fp_line
			(start 0.7874 -0.4064)
			(end 0.7874 0.4064)
			(stroke
				(width 0.1524)
				(type default)
			)
			(layer "F.SilkS")
		)
		(fp_line
			(start -0.67945 0.3048)
			(end -0.67945 -0.305054)
			(stroke
				(width 0.1)
				(type default)
			)
			(layer "F.Fab")
		)
		(fp_line
			(start -0.12065 0.3048)
			(end -0.67945 0.3048)
			(stroke
				(width 0.1)
				(type default)
			)
			(layer "F.Fab")
		)
		(fp_line
			(start 0.120396 0.3048)
			(end 0.120396 0.2794)
			(stroke
				(width 0.1)
				(type default)
			)
			(layer "F.Fab")
		)
		(fp_line
			(start 0.67945 0.3048)
			(end 0.120396 0.3048)
			(stroke
				(width 0.1)
				(type default)
			)
			(layer "F.Fab")
		)
		(fp_line
			(start -0.12065 0.2794)
			(end -0.12065 0.3048)
			(stroke
				(width 0.1)
				(type default)
			)
			(layer "F.Fab")
		)
		(fp_line
			(start 0.120396 0.2794)
			(end -0.12065 0.2794)
			(stroke
				(width 0.1)
				(type default)
			)
			(layer "F.Fab")
		)
		(fp_line
			(start -0.12065 -0.2794)
			(end 0.12065 -0.2794)
			(stroke
				(width 0.1)
				(type default)
			)
			(layer "F.Fab")
		)
		(fp_line
			(start 0.12065 -0.2794)
			(end 0.12065 -0.3048)
			(stroke
				(width 0.1)
				(type default)
			)
			(layer "F.Fab")
		)
		(fp_line
			(start 0.12065 -0.3048)
			(end 0.67945 -0.3048)
			(stroke
				(width 0.1)
				(type default)
			)
			(layer "F.Fab")
		)
		(fp_line
			(start 0.67945 -0.3048)
			(end 0.67945 0.3048)
			(stroke
				(width 0.1)
				(type default)
			)
			(layer "F.Fab")
		)
		(fp_line
			(start -0.67945 -0.305054)
			(end -0.12065 -0.305054)
			(stroke
				(width 0.1)
				(type default)
			)
			(layer "F.Fab")
		)
		(fp_line
			(start -0.12065 -0.305054)
			(end -0.12065 -0.2794)
			(stroke
				(width 0.1)
				(type default)
			)
			(layer "F.Fab")
		)
		(pad "1" smd circle
			(at -0.40005 0 270)
			(size 0 0)
			(layers "F.Cu" "F.Mask" "F.Paste")
			(net "MAX31790_U317_FREQ_START")
		)
		(pad "2" smd circle
			(at 0.40005 0 270)
			(size 0 0)
			(layers "F.Cu" "F.Mask" "F.Paste")
			(net "P3V3_AUX")
		)
	)
	(footprint ""
		(layer "F.Cu")
		(at 17.272 -146.05 90)
		(property "Reference" "R5523"
			(at 0 0 90)
			(layer "F.SilkS")
			(hide yes)
			(effects
				(font
					(size 1.27 1.27)
				)
			)
		)
		(property "Value" ""
			(at 0 0 90)
			(layer "F.Fab")
			(effects
				(font
					(size 1.27 1.27)
				)
			)
		)
		(duplicate_pad_numbers_are_jumpers no)
		(fp_line
			(start 0.7874 -0.4064)
			(end 0.7874 0.4064)
			(stroke
				(width 0.1524)
				(type default)
			)
			(layer "F.SilkS")
		)
		(fp_line
			(start -0.7874 -0.4064)
			(end 0.7874 -0.4064)
			(stroke
				(width 0.1524)
				(type default)
			)
			(layer "F.SilkS")
		)
		(fp_line
			(start 0.7874 0.4064)
			(end -0.7874 0.4064)
			(stroke
				(width 0.1524)
				(type default)
			)
			(layer "F.SilkS")
		)
		(fp_line
			(start -0.7874 0.4064)
			(end -0.7874 -0.4064)
			(stroke
				(width 0.1524)
				(type default)
			)
			(layer "F.SilkS")
		)
		(fp_line
			(start -0.12065 -0.305054)
			(end -0.12065 -0.2794)
			(stroke
				(width 0.1)
				(type default)
			)
			(layer "F.Fab")
		)
		(fp_line
			(start -0.67945 -0.305054)
			(end -0.12065 -0.305054)
			(stroke
				(width 0.1)
				(type default)
			)
			(layer "F.Fab")
		)
		(fp_line
			(start 0.67945 -0.3048)
			(end 0.67945 0.3048)
			(stroke
				(width 0.1)
				(type default)
			)
			(layer "F.Fab")
		)
		(fp_line
			(start 0.12065 -0.3048)
			(end 0.67945 -0.3048)
			(stroke
				(width 0.1)
				(type default)
			)
			(layer "F.Fab")
		)
		(fp_line
			(start 0.12065 -0.2794)
			(end 0.12065 -0.3048)
			(stroke
				(width 0.1)
				(type default)
			)
			(layer "F.Fab")
		)
		(fp_line
			(start -0.12065 -0.2794)
			(end 0.12065 -0.2794)
			(stroke
				(width 0.1)
				(type default)
			)
			(layer "F.Fab")
		)
		(fp_line
			(start 0.120396 0.2794)
			(end -0.12065 0.2794)
			(stroke
				(width 0.1)
				(type default)
			)
			(layer "F.Fab")
		)
		(fp_line
			(start -0.12065 0.2794)
			(end -0.12065 0.3048)
			(stroke
				(width 0.1)
				(type default)
			)
			(layer "F.Fab")
		)
		(fp_line
			(start 0.67945 0.3048)
			(end 0.120396 0.3048)
			(stroke
				(width 0.1)
				(type default)
			)
			(layer "F.Fab")
		)
		(fp_line
			(start 0.120396 0.3048)
			(end 0.120396 0.2794)
			(stroke
				(width 0.1)
				(type default)
			)
			(layer "F.Fab")
		)
		(fp_line
			(start -0.12065 0.3048)
			(end -0.67945 0.3048)
			(stroke
				(width 0.1)
				(type default)
			)
			(layer "F.Fab")
		)
		(fp_line
			(start -0.67945 0.3048)
			(end -0.67945 -0.305054)
			(stroke
				(width 0.1)
				(type default)
			)
			(layer "F.Fab")
		)
		(pad "1" smd circle
			(at -0.40005 0 90)
			(size 0 0)
			(layers "F.Cu" "F.Mask" "F.Paste")
			(net "P3V3_AUX")
		)
		(pad "2" smd circle
			(at 0.40005 0 90)
			(size 0 0)
			(layers "F.Cu" "F.Mask" "F.Paste")
			(net "PD_TCA9548_SML1_U321_A0")
		)
	)
	(footprint ""
		(layer "F.Cu")
		(at 35.179 -300.228 90)
		(property "Reference" "C2021"
			(at 0 0 90)
			(layer "F.SilkS")
			(hide yes)
			(effects
				(font
					(size 1.27 1.27)
				)
			)
		)
		(property "Value" ""
			(at 0 0 90)
			(layer "F.Fab")
			(effects
				(font
					(size 1.27 1.27)
				)
			)
		)
		(duplicate_pad_numbers_are_jumpers no)
		(fp_line
			(start 0.7874 -0.4064)
			(end 0.7874 0.4064)
			(stroke
				(width 0.1524)
				(type default)
			)
			(layer "F.SilkS")
		)
		(fp_line
			(start -0.7874 -0.4064)
			(end 0.7874 -0.4064)
			(stroke
				(width 0.1524)
				(type default)
			)
			(layer "F.SilkS")
		)
		(fp_line
			(start 0.7874 0.4064)
			(end -0.7874 0.4064)
			(stroke
				(width 0.1524)
				(type default)
			)
			(layer "F.SilkS")
		)
		(fp_line
			(start -0.7874 0.4064)
			(end -0.7874 -0.4064)
			(stroke
				(width 0.1524)
				(type default)
			)
			(layer "F.SilkS")
		)
		(fp_line
			(start -0.12065 -0.305054)
			(end -0.12065 -0.2794)
			(stroke
				(width 0.1)
				(type default)
			)
			(layer "F.Fab")
		)
		(fp_line
			(start -0.67945 -0.305054)
			(end -0.12065 -0.305054)
			(stroke
				(width 0.1)
				(type default)
			)
			(layer "F.Fab")
		)
		(fp_line
			(start 0.67945 -0.3048)
			(end 0.67945 0.3048)
			(stroke
				(width 0.1)
				(type default)
			)
			(layer "F.Fab")
		)
		(fp_line
			(start 0.12065 -0.3048)
			(end 0.67945 -0.3048)
			(stroke
				(width 0.1)
				(type default)
			)
			(layer "F.Fab")
		)
		(fp_line
			(start 0.12065 -0.2794)
			(end 0.12065 -0.3048)
			(stroke
				(width 0.1)
				(type default)
			)
			(layer "F.Fab")
		)
		(fp_line
			(start -0.12065 -0.2794)
			(end 0.12065 -0.2794)
			(stroke
				(width 0.1)
				(type default)
			)
			(layer "F.Fab")
		)
		(fp_line
			(start 0.120396 0.2794)
			(end -0.12065 0.2794)
			(stroke
				(width 0.1)
				(type default)
			)
			(layer "F.Fab")
		)
		(fp_line
			(start -0.12065 0.2794)
			(end -0.12065 0.3048)
			(stroke
				(width 0.1)
				(type default)
			)
			(layer "F.Fab")
		)
		(fp_line
			(start 0.67945 0.3048)
			(end 0.120396 0.3048)
			(stroke
				(width 0.1)
				(type default)
			)
			(layer "F.Fab")
		)
		(fp_line
			(start 0.120396 0.3048)
			(end 0.120396 0.2794)
			(stroke
				(width 0.1)
				(type default)
			)
			(layer "F.Fab")
		)
		(fp_line
			(start -0.12065 0.3048)
			(end -0.67945 0.3048)
			(stroke
				(width 0.1)
				(type default)
			)
			(layer "F.Fab")
		)
		(fp_line
			(start -0.67945 0.3048)
			(end -0.67945 -0.305054)
			(stroke
				(width 0.1)
				(type default)
			)
			(layer "F.Fab")
		)
		(pad "1" smd circle
			(at -0.40005 0 90)
			(size 0 0)
			(layers "F.Cu" "F.Mask" "F.Paste")
			(net "FAN_0_PWM_IL_R")
		)
		(pad "2" smd circle
			(at 0.40005 0 90)
			(size 0 0)
			(layers "F.Cu" "F.Mask" "F.Paste")
			(net "GND")
		)
	)
	(footprint ""
		(layer "F.Cu")
		(at 42.635932 -256.667)
		(property "Reference" "R5416"
			(at 0 0 0)
			(layer "F.SilkS")
			(hide yes)
			(effects
				(font
					(size 1.27 1.27)
				)
			)
		)
		(property "Value" ""
			(at 0 0 0)
			(layer "F.Fab")
			(effects
				(font
					(size 1.27 1.27)
				)
			)
		)
		(duplicate_pad_numbers_are_jumpers no)
		(fp_line
			(start -0.7874 -0.4064)
			(end 0.7874 -0.4064)
			(stroke
				(width 0.1524)
				(type default)
			)
			(layer "F.SilkS")
		)
		(fp_line
			(start -0.7874 0.4064)
			(end -0.7874 -0.4064)
			(stroke
				(width 0.1524)
				(type default)
			)
			(layer "F.SilkS")
		)
		(fp_line
			(start 0.7874 -0.4064)
			(end 0.7874 0.4064)
			(stroke
				(width 0.1524)
				(type default)
			)
			(layer "F.SilkS")
		)
		(fp_line
			(start 0.7874 0.4064)
			(end -0.7874 0.4064)
			(stroke
				(width 0.1524)
				(type default)
			)
			(layer "F.SilkS")
		)
		(fp_line
			(start -0.67945 -0.305054)
			(end -0.12065 -0.305054)
			(stroke
				(width 0.1)
				(type default)
			)
			(layer "F.Fab")
		)
		(fp_line
			(start -0.67945 0.3048)
			(end -0.67945 -0.305054)
			(stroke
				(width 0.1)
				(type default)
			)
			(layer "F.Fab")
		)
		(fp_line
			(start -0.12065 -0.305054)
			(end -0.12065 -0.2794)
			(stroke
				(width 0.1)
				(type default)
			)
			(layer "F.Fab")
		)
		(fp_line
			(start -0.12065 -0.2794)
			(end 0.12065 -0.2794)
			(stroke
				(width 0.1)
				(type default)
			)
			(layer "F.Fab")
		)
		(fp_line
			(start -0.12065 0.2794)
			(end -0.12065 0.3048)
			(stroke
				(width 0.1)
				(type default)
			)
			(layer "F.Fab")
		)
		(fp_line
			(start -0.12065 0.3048)
			(end -0.67945 0.3048)
			(stroke
				(width 0.1)
				(type default)
			)
			(layer "F.Fab")
		)
		(fp_line
			(start 0.120396 0.2794)
			(end -0.12065 0.2794)
			(stroke
				(width 0.1)
				(type default)
			)
			(layer "F.Fab")
		)
		(fp_line
			(start 0.120396 0.3048)
			(end 0.120396 0.2794)
			(stroke
				(width 0.1)
				(type default)
			)
			(layer "F.Fab")
		)
		(fp_line
			(start 0.12065 -0.3048)
			(end 0.67945 -0.3048)
			(stroke
				(width 0.1)
				(type default)
			)
			(layer "F.Fab")
		)
		(fp_line
			(start 0.12065 -0.2794)
			(end 0.12065 -0.3048)
			(stroke
				(width 0.1)
				(type default)
			)
			(layer "F.Fab")
		)
		(fp_line
			(start 0.67945 -0.3048)
			(end 0.67945 0.3048)
			(stroke
				(width 0.1)
				(type default)
			)
			(layer "F.Fab")
		)
		(fp_line
			(start 0.67945 0.3048)
			(end 0.120396 0.3048)
			(stroke
				(width 0.1)
				(type default)
			)
			(layer "F.Fab")
		)
		(pad "1" smd circle
			(at -0.40005 0)
			(size 0 0)
			(layers "F.Cu" "F.Mask" "F.Paste")
			(net "FAN_0_PRESENT_R")
		)
		(pad "2" smd circle
			(at 0.40005 0)
			(size 0 0)
			(layers "F.Cu" "F.Mask" "F.Paste")
			(net "FAN_0_PRESENT")
		)
	)
	(footprint ""
		(layer "F.Cu")
		(at 17.907 -169.291 180)
		(property "Reference" "R5499"
			(at 0 0 180)
			(layer "F.SilkS")
			(hide yes)
			(effects
				(font
					(size 1.27 1.27)
				)
			)
		)
		(property "Value" ""
			(at 0 0 180)
			(layer "F.Fab")
			(effects
				(font
					(size 1.27 1.27)
				)
			)
		)
		(duplicate_pad_numbers_are_jumpers no)
		(fp_line
			(start 0.7874 0.4064)
			(end -0.7874 0.4064)
			(stroke
				(width 0.1524)
				(type default)
			)
			(layer "F.SilkS")
		)
		(fp_line
			(start 0.7874 -0.4064)
			(end 0.7874 0.4064)
			(stroke
				(width 0.1524)
				(type default)
			)
			(layer "F.SilkS")
		)
		(fp_line
			(start -0.7874 0.4064)
			(end -0.7874 -0.4064)
			(stroke
				(width 0.1524)
				(type default)
			)
			(layer "F.SilkS")
		)
		(fp_line
			(start -0.7874 -0.4064)
			(end 0.7874 -0.4064)
			(stroke
				(width 0.1524)
				(type default)
			)
			(layer "F.SilkS")
		)
		(fp_line
			(start 0.67945 0.3048)
			(end 0.120396 0.3048)
			(stroke
				(width 0.1)
				(type default)
			)
			(layer "F.Fab")
		)
		(fp_line
			(start 0.67945 -0.3048)
			(end 0.67945 0.3048)
			(stroke
				(width 0.1)
				(type default)
			)
			(layer "F.Fab")
		)
		(fp_line
			(start 0.12065 -0.2794)
			(end 0.12065 -0.3048)
			(stroke
				(width 0.1)
				(type default)
			)
			(layer "F.Fab")
		)
		(fp_line
			(start 0.12065 -0.3048)
			(end 0.67945 -0.3048)
			(stroke
				(width 0.1)
				(type default)
			)
			(layer "F.Fab")
		)
		(fp_line
			(start 0.120396 0.3048)
			(end 0.120396 0.2794)
			(stroke
				(width 0.1)
				(type default)
			)
			(layer "F.Fab")
		)
		(fp_line
			(start 0.120396 0.2794)
			(end -0.12065 0.2794)
			(stroke
				(width 0.1)
				(type default)
			)
			(layer "F.Fab")
		)
		(fp_line
			(start -0.12065 0.3048)
			(end -0.67945 0.3048)
			(stroke
				(width 0.1)
				(type default)
			)
			(layer "F.Fab")
		)
		(fp_line
			(start -0.12065 0.2794)
			(end -0.12065 0.3048)
			(stroke
				(width 0.1)
				(type default)
			)
			(layer "F.Fab")
		)
		(fp_line
			(start -0.12065 -0.2794)
			(end 0.12065 -0.2794)
			(stroke
				(width 0.1)
				(type default)
			)
			(layer "F.Fab")
		)
		(fp_line
			(start -0.12065 -0.305054)
			(end -0.12065 -0.2794)
			(stroke
				(width 0.1)
				(type default)
			)
			(layer "F.Fab")
		)
		(fp_line
			(start -0.67945 0.3048)
			(end -0.67945 -0.305054)
			(stroke
				(width 0.1)
				(type default)
			)
			(layer "F.Fab")
		)
		(fp_line
			(start -0.67945 -0.305054)
			(end -0.12065 -0.305054)
			(stroke
				(width 0.1)
				(type default)
			)
			(layer "F.Fab")
		)
		(pad "1" smd circle
			(at -0.40005 0 180)
			(size 0 0)
			(layers "F.Cu" "F.Mask" "F.Paste")
			(net "FAN_4_PRESENT_R_N")
		)
		(pad "2" smd circle
			(at 0.40005 0 180)
			(size 0 0)
			(layers "F.Cu" "F.Mask" "F.Paste")
			(net "FAN_4_PRESENT_N")
		)
	)
)
